(kicad_pcb
	(version 20241229)
	(generator "pcbnew")
	(generator_version "9.0")
	(general
		(thickness 1.711)
		(legacy_teardrops no)
	)
	(paper "A4")
	(title_block
		(title "Antmicro Baseboard for Jetson AGX Thor")
		(date "2026-02-18")
		(rev "1.1.0")
		(company "Antmicro Ltd")
		(comment 1 "www.antmicro.com")
		(comment 9 "footprints 448-449 of 1170")
	)
	(layers
		(0 "F.Cu" signal)
		(4 "In1.Cu" signal)
		(6 "In2.Cu" signal)
		(8 "In3.Cu" signal)
		(10 "In4.Cu" jumper)
		(12 "In5.Cu" signal)
		(14 "In6.Cu" signal)
		(16 "In7.Cu" signal)
		(18 "In8.Cu" signal)
		(2 "B.Cu" signal)
		(9 "F.Adhes" user "F.Adhesive")
		(11 "B.Adhes" user "B.Adhesive")
		(13 "F.Paste" user)
		(15 "B.Paste" user)
		(5 "F.SilkS" user "F.Silkscreen")
		(7 "B.SilkS" user "B.Silkscreen")
		(1 "F.Mask" user)
		(3 "B.Mask" user)
		(17 "Dwgs.User" user "User.Drawings")
		(19 "Cmts.User" user "User.Comments")
		(21 "Eco1.User" user "User.Eco1")
		(23 "Eco2.User" user "User.Eco2")
		(25 "Edge.Cuts" user)
		(27 "Margin" user)
		(31 "F.CrtYd" user "F.Courtyard")
		(29 "B.CrtYd" user "B.Courtyard")
		(35 "F.Fab" user)
		(33 "B.Fab" user)
	)
	(footprint "antmicro-footprints:MLP44-24L_4x4x0.75mm"
		(layer "F.Cu")
		(at 181 128)
		(property "Reference" "U13"
			(at 0.475 3.29 0)
			(layer "F.SilkS")
			(effects
				(font
					(size 0.7 0.7)
					(thickness 0.15)
				)
				(justify left bottom)
			)
		)
		(property "Value" "SIC437AED-T1-GE3"
			(at -2.7 3.6 0)
			(layer "F.Fab")
			(effects
				(font
					(size 0.7 0.7)
					(thickness 0.15)
				)
				(justify left bottom)
			)
		)
		(property "Datasheet" "https://www.vishay.com/docs/75921/sic437.pdf"
			(at 0 0 0)
			(layer "F.Fab")
			(hide yes)
			(effects
				(font
					(size 1.27 1.27)
					(thickness 0.15)
				)
			)
		)
		(property "Description" "DC/DC Buck Step Down Regulator Adjustable, 4.5-28V In, 0.6V to 20V/12A Out, 1MHz, PowerPAK MLP44-24"
			(at 0 0 0)
			(layer "F.Fab")
			(hide yes)
			(effects
				(font
					(size 1.27 1.27)
					(thickness 0.15)
				)
			)
		)
		(property "Manufacturer" "Vishay"
			(at 0 0 0)
			(unlocked yes)
			(layer "F.Fab")
			(hide yes)
			(effects
				(font
					(size 1 1)
					(thickness 0.15)
				)
			)
		)
		(property "MPN" "SIC437AED-T1-GE3"
			(at 0 0 0)
			(unlocked yes)
			(layer "F.Fab")
			(hide yes)
			(effects
				(font
					(size 1 1)
					(thickness 0.15)
				)
			)
		)
		(property "Author" "Antmicro"
			(at 0 0 0)
			(unlocked yes)
			(layer "F.Fab")
			(hide yes)
			(effects
				(font
					(size 1 1)
					(thickness 0.15)
				)
			)
		)
		(property "License" "Apache-2.0"
			(at 0 0 0)
			(unlocked yes)
			(layer "F.Fab")
			(hide yes)
			(effects
				(font
					(size 1 1)
					(thickness 0.15)
				)
			)
		)
		(sheetname "/DCDC/")
		(sheetfile "dcdc.kicad_sch")
		(attr smd)
		(net_tie_pad_groups "1,2,26" "3,4,27" "5,6,7,8,9")
		(fp_line
			(start -2.11 -1.38)
			(end -2.11 -2.1)
			(stroke
				(width 0.15)
				(type solid)
			)
			(layer "F.SilkS")
		)
		(fp_line
			(start -2.11 2.11)
			(end -2.11 1.39)
			(stroke
				(width 0.15)
				(type solid)
			)
			(layer "F.SilkS")
		)
		(fp_line
			(start -1.89 -2.1)
			(end -2.11 -2.1)
			(stroke
				(width 0.15)
				(type solid)
			)
			(layer "F.SilkS")
		)
		(fp_line
			(start -1.89 2.11)
			(end -2.11 2.11)
			(stroke
				(width 0.15)
				(type solid)
			)
			(layer "F.SilkS")
		)
		(fp_line
			(start 1.44 2.11)
			(end 2.11 2.11)
			(stroke
				(width 0.15)
				(type solid)
			)
			(layer "F.SilkS")
		)
		(fp_line
			(start 1.89 -2.11)
			(end 2.11 -2.11)
			(stroke
				(width 0.15)
				(type solid)
			)
			(layer "F.SilkS")
		)
		(fp_line
			(start 2.11 -2.11)
			(end 2.11 -1.69)
			(stroke
				(width 0.15)
				(type solid)
			)
			(layer "F.SilkS")
		)
		(fp_line
			(start 2.11 2.11)
			(end 2.11 1.84)
			(stroke
				(width 0.15)
				(type solid)
			)
			(layer "F.SilkS")
		)
		(fp_circle
			(center -2.25 -1.15)
			(end -2.2 -1.15)
			(stroke
				(width 0.15)
				(type solid)
			)
			(fill yes)
			(layer "F.SilkS")
		)
		(fp_line
			(start -2.55 -2.55)
			(end 2.55 -2.55)
			(stroke
				(width 0.05)
				(type solid)
			)
			(layer "F.CrtYd")
		)
		(fp_line
			(start -2.55 2.55)
			(end -2.55 -2.55)
			(stroke
				(width 0.05)
				(type solid)
			)
			(layer "F.CrtYd")
		)
		(fp_line
			(start 2.55 -2.55)
			(end 2.55 2.55)
			(stroke
				(width 0.05)
				(type solid)
			)
			(layer "F.CrtYd")
		)
		(fp_line
			(start 2.55 2.55)
			(end -2.55 2.55)
			(stroke
				(width 0.05)
				(type solid)
			)
			(layer "F.CrtYd")
		)
		(fp_line
			(start -2 -1)
			(end -2 2)
			(stroke
				(width 0.15)
				(type solid)
			)
			(layer "F.Fab")
		)
		(fp_line
			(start -2 2)
			(end 2 2)
			(stroke
				(width 0.15)
				(type solid)
			)
			(layer "F.Fab")
		)
		(fp_line
			(start -1 -2)
			(end -2 -1)
			(stroke
				(width 0.15)
				(type solid)
			)
			(layer "F.Fab")
		)
		(fp_line
			(start 2 -2)
			(end -1 -2)
			(stroke
				(width 0.15)
				(type solid)
			)
			(layer "F.Fab")
		)
		(fp_line
			(start 2 2)
			(end 2 -2)
			(stroke
				(width 0.15)
				(type solid)
			)
			(layer "F.Fab")
		)
		(fp_text user "Author: Antmicro"
			(at -2.7 8 0)
			(layer "F.Fab")
			(effects
				(font
					(size 0.7 0.7)
					(thickness 0.15)
				)
				(justify left bottom)
			)
		)
		(fp_text user "License: Apache-2.0"
			(at -2.7 5.6 0)
			(layer "F.Fab")
			(effects
				(font
					(size 0.7 0.7)
					(thickness 0.15)
				)
				(justify left bottom)
			)
		)
		(fp_text user "${REFERENCE}"
			(at -2.7 6.8 0)
			(layer "F.Fab")
			(effects
				(font
					(size 0.7 0.7)
					(thickness 0.15)
				)
				(justify left bottom)
			)
		)
		(pad "1" smd roundrect
			(at -1.94 -0.825 90)
			(size 0.3 0.725)
			(layers "F.Cu" "F.Mask" "F.Paste")
			(roundrect_rratio 0.25)
			(net 13 "VCC")
			(pinfunction "V_{IN}")
			(pintype "power_in")
		)
		(pad "2" smd roundrect
			(at -1.94 -0.375 90)
			(size 0.3 0.725)
			(layers "F.Cu" "F.Mask" "F.Paste")
			(roundrect_rratio 0.25)
			(net 13 "VCC")
			(pinfunction "V_{IN}")
			(pintype "passive")
		)
		(pad "3" smd roundrect
			(at -1.94 0.525 90)
			(size 0.3 0.725)
			(layers "F.Cu" "F.Mask" "F.Paste")
			(roundrect_rratio 0.25)
			(net 1 "GND")
			(pinfunction "P_{GND}")
			(pintype "passive")
		)
		(pad "4" smd roundrect
			(at -1.94 0.975 90)
			(size 0.3 0.725)
			(layers "F.Cu" "F.Mask" "F.Paste")
			(roundrect_rratio 0.25)
			(net 1 "GND")
			(pinfunction "P_{GND}")
			(pintype "passive")
		)
		(pad "5" smd custom
			(at -1.475 1.94)
			(size 0.3 0.3)
			(layers "F.Cu" "F.Mask" "F.Paste")
			(net 1182 "/DCDC/3V3_SW")
			(pinfunction "SW")
			(pintype "passive")
			(options
				(clearance outline)
				(anchor circle)
			)
			(primitives
				(gr_poly
					(pts
						(xy -0.15 -0.2875) (xy -0.144291 -0.316201) (xy -0.128033 -0.340533) (xy -0.103701 -0.356791)
						(xy -0.075 -0.3625) (xy 0.075 -0.3625) (xy 0.103701 -0.356791) (xy 0.128033 -0.340533) (xy 0.144291 -0.316201)
						(xy 0.15 -0.2875) (xy 0.15 0.2875) (xy 0.144291 0.316201) (xy 0.128033 0.340533) (xy 0.103701 0.356791)
						(xy 0.075 0.3625) (xy -0.075 0.3625) (xy -0.103701 0.356791) (xy -0.128033 0.340533) (xy -0.144291 0.316201)
						(xy -0.15 0.2875)
					)
					(width 0)
					(fill yes)
				)
				(gr_poly
					(pts
						(xy -0.15 -0.3625) (xy 2.2 -0.3625) (xy 2.2 -0.0875) (xy -0.15 -0.0875)
					)
					(width 0)
					(fill yes)
				)
			)
		)
		(pad "6" smd roundrect
			(at -1.025 1.94)
			(size 0.3 0.725)
			(layers "F.Cu" "F.Mask" "F.Paste")
			(roundrect_rratio 0.25)
			(net 1182 "/DCDC/3V3_SW")
			(pinfunction "SW")
			(pintype "passive")
		)
		(pad "7" smd roundrect
			(at -0.575 1.94)
			(size 0.3 0.725)
			(layers "F.Cu" "F.Mask" "F.Paste")
			(roundrect_rratio 0.25)
			(net 1182 "/DCDC/3V3_SW")
			(pinfunction "SW")
			(pintype "passive")
		)
		(pad "8" smd roundrect
			(at 0.125 1.94)
			(size 0.3 0.725)
			(layers "F.Cu" "F.Mask" "F.Paste")
			(roundrect_rratio 0.25)
			(net 1182 "/DCDC/3V3_SW")
			(pinfunction "SW")
			(pintype "passive")
		)
		(pad "9" smd roundrect
			(at 0.575 1.94)
			(size 0.3 0.725)
			(layers "F.Cu" "F.Mask" "F.Paste")
			(roundrect_rratio 0.25)
			(net 1182 "/DCDC/3V3_SW")
			(pinfunction "SW")
			(pintype "passive")
		)
		(pad "10" smd roundrect
			(at 1.025 1.935)
			(size 0.3 0.725)
			(layers "F.Cu" "F.Mask" "F.Paste")
			(roundrect_rratio 0.25)
			(net 1059 "unconnected-(U13-GL-Pad10)_2")
			(pinfunction "GL")
			(pintype "passive+no_connect")
		)
		(pad "11" smd roundrect
			(at 1.94 1.425 90)
			(size 0.3 0.725)
			(layers "F.Cu" "F.Mask" "F.Paste")
			(roundrect_rratio 0.25)
			(net 1057 "unconnected-(U13-GL-Pad10)")
			(pinfunction "GL")
			(pintype "passive+no_connect")
		)
		(pad "12" smd roundrect
			(at 1.94 0.975 90)
			(size 0.3 0.725)
			(layers "F.Cu" "F.Mask" "F.Paste")
			(roundrect_rratio 0.25)
			(net 24 "/DCDC/3V3_VDRV")
			(pinfunction "V_{DRV}")
			(pintype "passive")
		)
		(pad "13" smd roundrect
			(at 1.94 0.525 90)
			(size 0.3 0.725)
			(layers "F.Cu" "F.Mask" "F.Paste")
			(roundrect_rratio 0.25)
			(net 1 "GND")
			(pinfunction "P_{GND}")
			(pintype "power_in")
		)
		(pad "14" smd roundrect
			(at 1.94 0.075 90)
			(size 0.3 0.725)
			(layers "F.Cu" "F.Mask" "F.Paste")
			(roundrect_rratio 0.25)
			(net 1056 "unconnected-(U13-P_{GOOD}-Pad14)")
			(pinfunction "P_{GOOD}")
			(pintype "output+no_connect")
		)
		(pad "15" smd roundrect
			(at 1.94 -0.375 90)
			(size 0.3 0.725)
			(layers "F.Cu" "F.Mask" "F.Paste")
			(roundrect_rratio 0.25)
			(net 19 "/DCDC/3V3_VDD")
			(pinfunction "V_{DD}")
			(pintype "passive")
		)
		(pad "16" smd roundrect
			(at 1.94 -0.825 90)
			(size 0.3 0.725)
			(layers "F.Cu" "F.Mask" "F.Paste")
			(roundrect_rratio 0.25)
			(net 1 "GND")
			(pinfunction "A_{GND}")
			(pintype "power_in")
		)
		(pad "17" smd roundrect
			(at 1.94 -1.275 90)
			(size 0.3 0.725)
			(layers "F.Cu" "F.Mask" "F.Paste")
			(roundrect_rratio 0.25)
			(net 1218 "/DCDC/3V3_FB")
			(pinfunction "FB")
			(pintype "passive")
		)
		(pad "18" smd roundrect
			(at 1.475 -1.94)
			(size 0.3 0.725)
			(layers "F.Cu" "F.Mask" "F.Paste")
			(roundrect_rratio 0.25)
			(net 567 "/DCDC/3V3_OUT")
			(pinfunction "V_{OUT}")
			(pintype "passive")
		)
		(pad "19" smd roundrect
			(at 1.025 -1.94)
			(size 0.3 0.725)
			(layers "F.Cu" "F.Mask" "F.Paste")
			(roundrect_rratio 0.25)
			(net 1293 "/DCDC/CARRIER_PWR_ON")
			(pinfunction "EN")
			(pintype "input")
		)
		(pad "20" smd roundrect
			(at 0.575 -1.94)
			(size 0.3 0.725)
			(layers "F.Cu" "F.Mask" "F.Paste")
			(roundrect_rratio 0.25)
			(net 1216 "/DCDC/3V3_MODE2")
			(pinfunction "MODE2")
			(pintype "input")
		)
		(pad "21" smd roundrect
			(at 0.125 -1.94)
			(size 0.3 0.725)
			(layers "F.Cu" "F.Mask" "F.Paste")
			(roundrect_rratio 0.25)
			(net 1213 "/DCDC/3V3_MODE1")
			(pinfunction "MODE1")
			(pintype "input")
		)
		(pad "22" smd roundrect
			(at -0.575 -1.94)
			(size 0.3 0.725)
			(layers "F.Cu" "F.Mask" "F.Paste")
			(roundrect_rratio 0.25)
			(net 13 "VCC")
			(pinfunction "V_{IN}")
			(pintype "passive")
		)
		(pad "23" smd roundrect
			(at -1.025 -1.94)
			(size 0.3 0.725)
			(layers "F.Cu" "F.Mask" "F.Paste")
			(roundrect_rratio 0.25)
			(net 28 "/DCDC/3V3_BOOT")
			(pinfunction "BOOT")
			(pintype "passive")
		)
		(pad "24" smd roundrect
			(at -1.475 -1.94)
			(size 0.3 0.725)
			(layers "F.Cu" "F.Mask" "F.Paste")
			(roundrect_rratio 0.25)
			(net 29 "/DCDC/3V3_PHASE")
			(pinfunction "PHASE")
			(pintype "passive")
		)
		(pad "25" smd rect
			(at 0.49 -0.75 180)
			(size 1.575 1.05)
			(layers "F.Cu" "F.Mask" "F.Paste")
			(net 1 "GND")
			(pinfunction "A_{GND}")
			(pintype "passive")
		)
		(pad "26" smd rect
			(at -1.175 -0.75 180)
			(size 1.15 1.05)
			(layers "F.Cu" "F.Mask" "F.Paste")
			(net 13 "VCC")
			(pinfunction "V_{IN}")
			(pintype "passive")
		)
		(pad "27" smd custom
			(at -0.75 0.775)
			(size 1 1)
			(layers "F.Cu" "F.Mask" "F.Paste")
			(net 1 "GND")
			(pinfunction "P_{GND}")
			(pintype "passive")
			(options
				(clearance outline)
				(anchor rect)
			)
			(primitives
				(gr_poly
					(pts
						(xy -1 0.5) (xy -1 -0.7) (xy 1.825 -0.7) (xy 1.825 -0.245) (xy 1.175 -0.245) (xy 1.175 0.5)
					)
					(width 0)
					(fill yes)
				)
			)
		)
		(pad "28" smd rect
			(at 0.985 0.99 180)
			(size 0.58 0.38)
			(layers "F.Cu" "F.Mask" "F.Paste")
			(net 1058 "unconnected-(U13-GL-Pad10)_1")
			(pinfunction "GL")
			(pintype "passive+no_connect")
		)
	)
	(footprint "antmicro-footprints:C_0805_2012Metric"
		(layer "F.Cu")
		(at 172.37 110.346 90)
		(descr "Capacitor SMD 0805")
		(tags "capacitor SMD 0805")
		(property "Reference" "C267"
			(at 1.79 0.36 90)
			(layer "F.SilkS")
			(effects
				(font
					(size 0.7 0.7)
					(thickness 0.15)
				)
				(justify left bottom)
			)
		)
		(property "Value" "C_22u_25V_0805"
			(at -2.055717 1.963152 90)
			(layer "F.Fab")
			(effects
				(font
					(size 0.7 0.7)
					(thickness 0.15)
				)
				(justify left bottom)
			)
		)
		(property "Datasheet" "https://product.samsungsem.com/mlcc/CL21A226MAYNNN.do"
			(at 0 0 90)
			(layer "F.Fab")
			(hide yes)
			(effects
				(font
					(size 1.27 1.27)
					(thickness 0.15)
				)
			)
		)
		(property "Description" "SMT Multilayer Ceramic Capacitor, 22uF, +/-20%, 25V, X5R, 0805 [2012 Metric]"
			(at 0 0 90)
			(layer "F.Fab")
			(hide yes)
			(effects
				(font
					(size 1.27 1.27)
					(thickness 0.15)
				)
			)
		)
		(property "MPN" "CL21A226MAYNNNE"
			(at 0 0 90)
			(unlocked yes)
			(layer "F.Fab")
			(hide yes)
			(effects
				(font
					(size 1 1)
					(thickness 0.15)
				)
			)
		)
		(property "Manufacturer" "Samsung Electro-Mechanics"
			(at 0 0 90)
			(unlocked yes)
			(layer "F.Fab")
			(hide yes)
			(effects
				(font
					(size 1 1)
					(thickness 0.15)
				)
			)
		)
		(property "License" "Apache-2.0"
			(at 0 0 90)
			(unlocked yes)
			(layer "F.Fab")
			(hide yes)
			(effects
				(font
					(size 1 1)
					(thickness 0.15)
				)
			)
		)
		(property "Author" "Antmicro"
			(at 0 0 90)
			(unlocked yes)
			(layer "F.Fab")
			(hide yes)
			(effects
				(font
					(size 1 1)
					(thickness 0.15)
				)
			)
		)
		(property "Val" "22u"
			(at 0 0 90)
			(unlocked yes)
			(layer "F.Fab")
			(hide yes)
			(effects
				(font
					(size 1 1)
					(thickness 0.15)
				)
			)
		)
		(property "Voltage" "25V"
			(at 0 0 90)
			(unlocked yes)
			(layer "F.Fab")
			(hide yes)
			(effects
				(font
					(size 1 1)
					(thickness 0.15)
				)
			)
		)
		(property "Dielectric" "X5R"
			(at 0 0 90)
			(unlocked yes)
			(layer "F.Fab")
			(hide yes)
			(effects
				(font
					(size 1 1)
					(thickness 0.15)
				)
			)
		)
		(property "Public" "False"
			(at 0 0 90)
			(unlocked yes)
			(layer "F.Fab")
			(hide yes)
			(effects
				(font
					(size 1 1)
					(thickness 0.15)
				)
			)
		)
		(sheetname "/DCDC/")
		(sheetfile "dcdc.kicad_sch")
		(attr smd)
		(fp_line
			(start -0.3 -0.7)
			(end 0.3 -0.7)
			(stroke
				(width 0.15)
				(type solid)
			)
			(layer "F.SilkS")
		)
		(fp_line
			(start -0.3 0.7)
			(end 0.3 0.7)
			(stroke
				(width 0.15)
				(type solid)
			)
			(layer "F.SilkS")
		)
		(fp_rect
			(start 1.95 -0.9)
			(end -1.95 0.9)
			(stroke
				(width 0.05)
				(type default)
			)
			(fill no)
			(layer "F.CrtYd")
		)
		(fp_rect
			(start -0.95 -0.675)
			(end 0.95 0.675)
			(stroke
				(width 0.15)
				(type solid)
			)
			(fill no)
			(layer "F.Fab")
		)
		(fp_text user "Author: Antmicro"
			(at -1.9 5.947 90)
			(layer "F.Fab")
			(effects
				(font
					(size 0.7 0.7)
					(thickness 0.15)
				)
				(justify left bottom)
			)
		)
		(fp_text user "${REFERENCE}"
			(at -1.9 3.947 90)
			(layer "F.Fab")
			(effects
				(font
					(size 0.7 0.7)
					(thickness 0.15)
				)
				(justify left bottom)
			)
		)
		(fp_text user "License: Apache-2.0"
			(at -1.9 4.947 90)
			(layer "F.Fab")
			(effects
				(font
					(size 0.7 0.7)
					(thickness 0.15)
				)
				(justify left bottom)
			)
		)
		(pad "1" smd roundrect
			(at -1.1 0 90)
			(size 1.2 1.3)
			(layers "F.Cu" "F.Mask" "F.Paste")
			(roundrect_rratio 0.25)
			(net 1 "GND")
			(pintype "passive")
		)
		(pad "2" smd roundrect
			(at 1.1 0 90)
			(size 1.2 1.3)
			(layers "F.Cu" "F.Mask" "F.Paste")
			(roundrect_rratio 0.25)
			(net 13 "VCC")
			(pintype "passive")
		)
	)
)
